(kicad_pcb
	(version 20260206)
	(generator "pcbnew")
	(generator_version "10.0")
	(general
		(thickness 1.6)
		(legacy_teardrops no)
	)
	(paper "A4")
	(title_block
		(title "04192023_DAF0TMB3IC0_F0TG_MB_C_brd_V02_OCP.brd")
		(comment 1 "Grand Teton / footprints 8281-8287 of 8354")
	)
	(layers
		(0 "F.Cu" signal "TOP")
		(4 "In1.Cu" signal "GND")
		(6 "In2.Cu" signal "IN1")
		(8 "In3.Cu" signal "GND1")
		(10 "In4.Cu" signal "IN2")
		(12 "In5.Cu" signal "GND2")
		(14 "In6.Cu" signal "IN3")
		(16 "In7.Cu" signal "GND3")
		(18 "In8.Cu" signal "VCC")
		(20 "In9.Cu" signal "VCC1")
		(22 "In10.Cu" signal "GND4")
		(24 "In11.Cu" signal "IN4")
		(26 "In12.Cu" signal "GND5")
		(28 "In13.Cu" signal "IN5")
		(30 "In14.Cu" signal "GND6")
		(32 "In15.Cu" signal "IN6")
		(34 "In16.Cu" signal "GND7")
		(2 "B.Cu" signal "BOTTOM")
		(9 "F.Adhes" user "F.Adhesive")
		(11 "B.Adhes" user "B.Adhesive")
		(13 "F.Paste" user "Package Geometry/Pastemask Top")
		(15 "B.Paste" user "Package Geometry/Pastemask Bottom")
		(5 "F.SilkS" user "Ref Des/Silkscreen Top")
		(7 "B.SilkS" user "Ref Des/Silkscreen Bottom")
		(1 "F.Mask" user "Board Geometry/Soldermask Top")
		(3 "B.Mask" user "Board Geometry/Soldermask Bottom")
		(17 "Dwgs.User" user "User.Drawings")
		(19 "Cmts.User" user "User.Comments")
		(21 "Eco1.User" user "User.Eco1")
		(23 "Eco2.User" user "User.Eco2")
		(25 "Edge.Cuts" user "Board Geometry/Outline")
		(27 "Margin" user)
		(31 "F.CrtYd" user "Package Geometry/Place Bound Top")
		(29 "B.CrtYd" user "Package Geometry/Place Bound Bottom")
		(35 "F.Fab" user "Ref Des/Assembly Top")
		(33 "B.Fab" user "Ref Des/Assembly Bottom")
	)
	(footprint ""
		(layer "B.Cu")
		(at 509.384808 -147.926806 90)
		(property "Reference" "X25"
			(at 0.885444 3.130042 270)
			(unlocked yes)
			(layer "B.SilkS")
			(effects
				(font
					(size 0.7874 0.5842)
					(thickness 0.1524)
				)
				(justify left mirror)
			)
		)
		(property "Value" ""
			(at 0 0 90)
			(layer "B.Fab")
			(effects
				(font
					(size 1.27 1.27)
				)
				(justify mirror)
			)
		)
		(property "Device Type" "TP_TDR_4P_FTS_TH-TP_TDR_4P_DIP,EMPTY,TP15"
			(at -1.30175 1.27 0)
			(unlocked yes)
			(layer "B.Fab")
			(hide yes)
			(effects
				(font
					(size 0.635 0.4064)
					(thickness 0.1524)
				)
				(justify mirror)
			)
		)
		(property "User Part Number" "N_A"
			(at -1.30175 1.27 0)
			(unlocked yes)
			(layer "Cmts.User")
			(hide yes)
			(effects
				(font
					(size 0.635 0.4064)
					(thickness 0.1524)
				)
				(justify mirror)
			)
		)
		(duplicate_pad_numbers_are_jumpers no)
		(fp_line
			(start 0 -1.27)
			(end 0 -0.635)
			(stroke
				(width 0.1524)
				(type default)
			)
			(layer "B.SilkS")
		)
		(fp_line
			(start -2.54 -1.27)
			(end 0 -1.27)
			(stroke
				(width 0.1524)
				(type default)
			)
			(layer "B.SilkS")
		)
		(fp_line
			(start -2.54 -1.1303)
			(end -2.54 -1.27)
			(stroke
				(width 0.1524)
				(type default)
			)
			(layer "B.SilkS")
		)
		(fp_line
			(start 0 0.635)
			(end 0 1.905)
			(stroke
				(width 0.1524)
				(type default)
			)
			(layer "B.SilkS")
		)
		(fp_line
			(start -2.54 1.4097)
			(end -2.54 1.1303)
			(stroke
				(width 0.1524)
				(type default)
			)
			(layer "B.SilkS")
		)
		(fp_line
			(start 0 3.175)
			(end 0 3.81)
			(stroke
				(width 0.1524)
				(type default)
			)
			(layer "B.SilkS")
		)
		(fp_line
			(start 0 3.81)
			(end -2.54 3.81)
			(stroke
				(width 0.1524)
				(type default)
			)
			(layer "B.SilkS")
		)
		(fp_line
			(start -2.54 3.81)
			(end -2.54 3.6703)
			(stroke
				(width 0.1524)
				(type default)
			)
			(layer "B.SilkS")
		)
		(fp_poly
			(pts
				(xy 2.285746 -0.762) (xy 2.285746 0.762) (xy 0.761746 0)
			)
			(stroke
				(width 0)
				(type default)
			)
			(fill yes)
			(layer "B.SilkS")
		)
		(fp_line
			(start 0 -1.27)
			(end 0 3.81)
			(stroke
				(width 0.1)
				(type default)
			)
			(layer "B.Fab")
		)
		(fp_line
			(start -2.54 -1.27)
			(end 0 -1.27)
			(stroke
				(width 0.1)
				(type default)
			)
			(layer "B.Fab")
		)
		(fp_line
			(start 0 3.81)
			(end -2.54 3.81)
			(stroke
				(width 0.1)
				(type default)
			)
			(layer "B.Fab")
		)
		(fp_line
			(start -2.54 3.81)
			(end -2.54 -1.27)
			(stroke
				(width 0.1)
				(type default)
			)
			(layer "B.Fab")
		)
		(fp_poly
			(pts
				(xy 0.761746 0) (xy 2.285746 -0.762) (xy 2.285746 0.762)
			)
			(stroke
				(width 0)
				(type default)
			)
			(fill yes)
			(layer "B.Fab")
		)
		(pad "1" thru_hole circle
			(at 0 0 270)
			(size 1.0033 1.0033)
			(drill 0.249936)
			(layers "*.Cu" "*.Mask")
			(remove_unused_layers no)
			(net "TDR_DIFF_80_IN5_DP")
			(clearance 0.10795)
			(padstack
				(mode front_inner_back)
				(layer "Inner"
					(shape circle)
					(size 0.8001 0.8001)
					(clearance 0.1524)
				)
				(layer "B.Cu"
					(shape circle)
					(size 1.0033 1.0033)
					(thermal_gap 0.10795)
					(clearance 0.10795)
				)
			)
		)
		(pad "2" thru_hole circle
			(at -2.54 0 270)
			(size 1.9939 1.9939)
			(drill 0.249936)
			(layers "*.Cu" "*.Mask")
			(remove_unused_layers no)
			(net "T1_GND")
			(clearance 0.10795)
			(padstack
				(mode front_inner_back)
				(layer "Inner"
					(shape circle)
					(size 0.8001 0.8001)
					(clearance 0.1524)
				)
				(layer "B.Cu"
					(shape circle)
					(size 1.9939 1.9939)
					(thermal_gap 0.10795)
					(clearance 0.10795)
				)
			)
		)
		(pad "3" thru_hole circle
			(at -2.54 2.54 270)
			(size 1.9939 1.9939)
			(drill 0.249936)
			(layers "*.Cu" "*.Mask")
			(remove_unused_layers no)
			(net "T1_GND")
			(clearance 0.10795)
			(padstack
				(mode front_inner_back)
				(layer "Inner"
					(shape circle)
					(size 0.8001 0.8001)
					(clearance 0.1524)
				)
				(layer "B.Cu"
					(shape circle)
					(size 1.9939 1.9939)
					(thermal_gap 0.10795)
					(clearance 0.10795)
				)
			)
		)
		(pad "4" thru_hole circle
			(at 0 2.54 270)
			(size 1.0033 1.0033)
			(drill 0.249936)
			(layers "*.Cu" "*.Mask")
			(remove_unused_layers no)
			(net "TDR_DIFF_80_IN5_DN")
			(clearance 0.10795)
			(padstack
				(mode front_inner_back)
				(layer "Inner"
					(shape circle)
					(size 0.8001 0.8001)
					(clearance 0.1524)
				)
				(layer "B.Cu"
					(shape circle)
					(size 1.0033 1.0033)
					(thermal_gap 0.10795)
					(clearance 0.10795)
				)
			)
		)
	)
	(footprint ""
		(layer "B.Cu")
		(at 407.543254 -162.237928 -90)
		(property "Reference" "PC8010"
			(at 0 0 90)
			(layer "B.SilkS")
			(hide yes)
			(effects
				(font
					(size 1.27 1.27)
				)
				(justify mirror)
			)
		)
		(property "Value" ""
			(at 0 0 90)
			(layer "B.Fab")
			(effects
				(font
					(size 1.27 1.27)
				)
				(justify mirror)
			)
		)
		(duplicate_pad_numbers_are_jumpers no)
		(fp_line
			(start -1.524 0.762)
			(end 1.524 0.762)
			(stroke
				(width 0.1524)
				(type default)
			)
			(layer "B.SilkS")
		)
		(fp_line
			(start 1.524 0.762)
			(end 1.524 -0.762)
			(stroke
				(width 0.1524)
				(type default)
			)
			(layer "B.SilkS")
		)
		(fp_line
			(start -1.524 -0.762)
			(end -1.524 0.762)
			(stroke
				(width 0.1524)
				(type default)
			)
			(layer "B.SilkS")
		)
		(fp_line
			(start 1.524 -0.762)
			(end -1.524 -0.762)
			(stroke
				(width 0.1524)
				(type default)
			)
			(layer "B.SilkS")
		)
		(fp_line
			(start -1.1049 0.724916)
			(end -1.1049 -0.724916)
			(stroke
				(width 0.1)
				(type default)
			)
			(layer "B.Fab")
		)
		(fp_line
			(start 1.1049 0.724916)
			(end -1.1049 0.724916)
			(stroke
				(width 0.1)
				(type default)
			)
			(layer "B.Fab")
		)
		(fp_line
			(start -1.1049 -0.724916)
			(end 1.1049 -0.724916)
			(stroke
				(width 0.1)
				(type default)
			)
			(layer "B.Fab")
		)
		(fp_line
			(start 1.1049 -0.724916)
			(end 1.1049 0.724916)
			(stroke
				(width 0.1)
				(type default)
			)
			(layer "B.Fab")
		)
		(pad "1" smd rect
			(at 0.889 0 270)
			(size 1.016 1.27)
			(layers "B.Cu" "B.Mask" "B.Paste")
			(net "SW_P12V_AUX_PVDDCR_SOC_P0_FLT")
		)
		(pad "2" smd rect
			(at -0.889 0 270)
			(size 1.016 1.27)
			(layers "B.Cu" "B.Mask" "B.Paste")
			(net "GND")
		)
	)
	(footprint ""
		(layer "B.Cu")
		(at 119.463566 -408.517344 90)
		(property "Reference" "C6728"
			(at 0 0 90)
			(layer "B.SilkS")
			(hide yes)
			(effects
				(font
					(size 1.27 1.27)
				)
				(justify mirror)
			)
		)
		(property "Value" ""
			(at 0 0 90)
			(layer "B.Fab")
			(effects
				(font
					(size 1.27 1.27)
				)
				(justify mirror)
			)
		)
		(duplicate_pad_numbers_are_jumpers no)
		(fp_line
			(start 0.299974 -0.150114)
			(end -0.299974 -0.150114)
			(stroke
				(width 0.1)
				(type default)
			)
			(layer "B.Fab")
		)
		(fp_line
			(start -0.299974 -0.150114)
			(end -0.299974 0.150114)
			(stroke
				(width 0.1)
				(type default)
			)
			(layer "B.Fab")
		)
		(fp_line
			(start 0.299974 0.150114)
			(end 0.299974 -0.150114)
			(stroke
				(width 0.1)
				(type default)
			)
			(layer "B.Fab")
		)
		(fp_line
			(start -0.299974 0.150114)
			(end 0.299974 0.150114)
			(stroke
				(width 0.1)
				(type default)
			)
			(layer "B.Fab")
		)
		(pad "1" smd rect
			(at 0.2667 0 270)
			(size 0.3048 0.381)
			(layers "B.Cu" "B.Mask" "B.Paste")
			(net "P5E_CPU1_P3_TX_BUF_C_DN<1>")
		)
		(pad "2" smd rect
			(at -0.2667 0 270)
			(size 0.3048 0.381)
			(layers "B.Cu" "B.Mask" "B.Paste")
			(net "P5E_CPU1_P3_TX_BUF_DN<1>")
		)
	)
	(footprint ""
		(layer "B.Cu")
		(at 44.340272 -192.66027)
		(property "Reference" "C179"
			(at 0 0 0)
			(layer "B.SilkS")
			(hide yes)
			(effects
				(font
					(size 1.27 1.27)
				)
				(justify mirror)
			)
		)
		(property "Value" ""
			(at 0 0 0)
			(layer "B.Fab")
			(effects
				(font
					(size 1.27 1.27)
				)
				(justify mirror)
			)
		)
		(duplicate_pad_numbers_are_jumpers no)
		(fp_line
			(start -1.524 -0.762)
			(end -1.524 0.762)
			(stroke
				(width 0.1524)
				(type default)
			)
			(layer "B.SilkS")
		)
		(fp_line
			(start -1.524 0.762)
			(end 1.524 0.762)
			(stroke
				(width 0.1524)
				(type default)
			)
			(layer "B.SilkS")
		)
		(fp_line
			(start 1.524 -0.762)
			(end -1.524 -0.762)
			(stroke
				(width 0.1524)
				(type default)
			)
			(layer "B.SilkS")
		)
		(fp_line
			(start 1.524 0.762)
			(end 1.524 -0.762)
			(stroke
				(width 0.1524)
				(type default)
			)
			(layer "B.SilkS")
		)
		(fp_line
			(start -1.1049 -0.724916)
			(end 1.1049 -0.724916)
			(stroke
				(width 0.1)
				(type default)
			)
			(layer "B.Fab")
		)
		(fp_line
			(start -1.1049 0.724916)
			(end -1.1049 -0.724916)
			(stroke
				(width 0.1)
				(type default)
			)
			(layer "B.Fab")
		)
		(fp_line
			(start 1.1049 -0.724916)
			(end 1.1049 0.724916)
			(stroke
				(width 0.1)
				(type default)
			)
			(layer "B.Fab")
		)
		(fp_line
			(start 1.1049 0.724916)
			(end -1.1049 0.724916)
			(stroke
				(width 0.1)
				(type default)
			)
			(layer "B.Fab")
		)
		(pad "1" smd rect
			(at 0.889 0)
			(size 1.016 1.27)
			(layers "B.Cu" "B.Mask" "B.Paste")
			(net "P12V_MEM_CPU1")
		)
		(pad "2" smd rect
			(at -0.889 0)
			(size 1.016 1.27)
			(layers "B.Cu" "B.Mask" "B.Paste")
			(net "GND")
		)
	)
	(footprint ""
		(layer "B.Cu")
		(at 266.30376 -193.99631)
		(property "Reference" "R94"
			(at 0 0 0)
			(layer "B.SilkS")
			(hide yes)
			(effects
				(font
					(size 1.27 1.27)
				)
				(justify mirror)
			)
		)
		(property "Value" ""
			(at 0 0 0)
			(layer "B.Fab")
			(effects
				(font
					(size 1.27 1.27)
				)
				(justify mirror)
			)
		)
		(duplicate_pad_numbers_are_jumpers no)
		(fp_line
			(start -0.7874 -0.4064)
			(end -0.7874 0.4064)
			(stroke
				(width 0.1524)
				(type default)
			)
			(layer "B.SilkS")
		)
		(fp_line
			(start -0.7874 0.4064)
			(end 0.7874 0.4064)
			(stroke
				(width 0.1524)
				(type default)
			)
			(layer "B.SilkS")
		)
		(fp_line
			(start 0.7874 -0.4064)
			(end -0.7874 -0.4064)
			(stroke
				(width 0.1524)
				(type default)
			)
			(layer "B.SilkS")
		)
		(fp_line
			(start 0.7874 0.4064)
			(end 0.7874 -0.4064)
			(stroke
				(width 0.1524)
				(type default)
			)
			(layer "B.SilkS")
		)
		(fp_line
			(start -0.67945 -0.3048)
			(end -0.67945 0.3048)
			(stroke
				(width 0.1)
				(type default)
			)
			(layer "B.Fab")
		)
		(fp_line
			(start -0.67945 0.3048)
			(end -0.120396 0.3048)
			(stroke
				(width 0.1)
				(type default)
			)
			(layer "B.Fab")
		)
		(fp_line
			(start -0.12065 -0.3048)
			(end -0.67945 -0.3048)
			(stroke
				(width 0.1)
				(type default)
			)
			(layer "B.Fab")
		)
		(fp_line
			(start -0.12065 -0.2794)
			(end -0.12065 -0.3048)
			(stroke
				(width 0.1)
				(type default)
			)
			(layer "B.Fab")
		)
		(fp_line
			(start -0.120396 0.2794)
			(end 0.12065 0.2794)
			(stroke
				(width 0.1)
				(type default)
			)
			(layer "B.Fab")
		)
		(fp_line
			(start -0.120396 0.3048)
			(end -0.120396 0.2794)
			(stroke
				(width 0.1)
				(type default)
			)
			(layer "B.Fab")
		)
		(fp_line
			(start 0.12065 -0.305054)
			(end 0.12065 -0.2794)
			(stroke
				(width 0.1)
				(type default)
			)
			(layer "B.Fab")
		)
		(fp_line
			(start 0.12065 -0.2794)
			(end -0.12065 -0.2794)
			(stroke
				(width 0.1)
				(type default)
			)
			(layer "B.Fab")
		)
		(fp_line
			(start 0.12065 0.2794)
			(end 0.12065 0.3048)
			(stroke
				(width 0.1)
				(type default)
			)
			(layer "B.Fab")
		)
		(fp_line
			(start 0.12065 0.3048)
			(end 0.67945 0.3048)
			(stroke
				(width 0.1)
				(type default)
			)
			(layer "B.Fab")
		)
		(fp_line
			(start 0.67945 -0.305054)
			(end 0.12065 -0.305054)
			(stroke
				(width 0.1)
				(type default)
			)
			(layer "B.Fab")
		)
		(fp_line
			(start 0.67945 0.3048)
			(end 0.67945 -0.305054)
			(stroke
				(width 0.1)
				(type default)
			)
			(layer "B.Fab")
		)
		(pad "1" smd circle
			(at 0.40005 0 180)
			(size 0 0)
			(layers "B.Cu" "B.Mask" "B.Paste")
			(net "P3V3")
		)
		(pad "2" smd circle
			(at -0.40005 0 180)
			(size 0 0)
			(layers "B.Cu" "B.Mask" "B.Paste")
			(net "PWRGD_CHF_CPU0_DIMM")
		)
	)
	(footprint ""
		(layer "B.Cu")
		(at 144.927574 -314.49391 180)
		(property "Reference" "R550"
			(at 0 0 0)
			(layer "B.SilkS")
			(hide yes)
			(effects
				(font
					(size 1.27 1.27)
				)
				(justify mirror)
			)
		)
		(property "Value" ""
			(at 0 0 0)
			(layer "B.Fab")
			(effects
				(font
					(size 1.27 1.27)
				)
				(justify mirror)
			)
		)
		(duplicate_pad_numbers_are_jumpers no)
		(fp_line
			(start 0.7874 0.4064)
			(end 0.7874 -0.4064)
			(stroke
				(width 0.1524)
				(type default)
			)
			(layer "B.SilkS")
		)
		(fp_line
			(start 0.7874 -0.4064)
			(end -0.7874 -0.4064)
			(stroke
				(width 0.1524)
				(type default)
			)
			(layer "B.SilkS")
		)
		(fp_line
			(start -0.7874 0.4064)
			(end 0.7874 0.4064)
			(stroke
				(width 0.1524)
				(type default)
			)
			(layer "B.SilkS")
		)
		(fp_line
			(start -0.7874 -0.4064)
			(end -0.7874 0.4064)
			(stroke
				(width 0.1524)
				(type default)
			)
			(layer "B.SilkS")
		)
		(fp_line
			(start 0.67945 0.3048)
			(end 0.67945 -0.305054)
			(stroke
				(width 0.1)
				(type default)
			)
			(layer "B.Fab")
		)
		(fp_line
			(start 0.67945 -0.305054)
			(end 0.12065 -0.305054)
			(stroke
				(width 0.1)
				(type default)
			)
			(layer "B.Fab")
		)
		(fp_line
			(start 0.12065 0.3048)
			(end 0.67945 0.3048)
			(stroke
				(width 0.1)
				(type default)
			)
			(layer "B.Fab")
		)
		(fp_line
			(start 0.12065 0.2794)
			(end 0.12065 0.3048)
			(stroke
				(width 0.1)
				(type default)
			)
			(layer "B.Fab")
		)
		(fp_line
			(start 0.12065 -0.2794)
			(end -0.12065 -0.2794)
			(stroke
				(width 0.1)
				(type default)
			)
			(layer "B.Fab")
		)
		(fp_line
			(start 0.12065 -0.305054)
			(end 0.12065 -0.2794)
			(stroke
				(width 0.1)
				(type default)
			)
			(layer "B.Fab")
		)
		(fp_line
			(start -0.120396 0.3048)
			(end -0.120396 0.2794)
			(stroke
				(width 0.1)
				(type default)
			)
			(layer "B.Fab")
		)
		(fp_line
			(start -0.120396 0.2794)
			(end 0.12065 0.2794)
			(stroke
				(width 0.1)
				(type default)
			)
			(layer "B.Fab")
		)
		(fp_line
			(start -0.12065 -0.2794)
			(end -0.12065 -0.3048)
			(stroke
				(width 0.1)
				(type default)
			)
			(layer "B.Fab")
		)
		(fp_line
			(start -0.12065 -0.3048)
			(end -0.67945 -0.3048)
			(stroke
				(width 0.1)
				(type default)
			)
			(layer "B.Fab")
		)
		(fp_line
			(start -0.67945 0.3048)
			(end -0.120396 0.3048)
			(stroke
				(width 0.1)
				(type default)
			)
			(layer "B.Fab")
		)
		(fp_line
			(start -0.67945 -0.3048)
			(end -0.67945 0.3048)
			(stroke
				(width 0.1)
				(type default)
			)
			(layer "B.Fab")
		)
		(pad "1" smd circle
			(at 0.40005 0)
			(size 0 0)
			(layers "B.Cu" "B.Mask" "B.Paste")
			(net "CPU1_SMERR_N")
		)
		(pad "2" smd circle
			(at -0.40005 0)
			(size 0 0)
			(layers "B.Cu" "B.Mask" "B.Paste")
			(net "PVDD18_S5_P1")
		)
	)
	(footprint ""
		(layer "B.Cu")
		(at 90.209878 -149.96541 180)
		(property "Reference" "PR172"
			(at 0 0 0)
			(layer "B.SilkS")
			(hide yes)
			(effects
				(font
					(size 1.27 1.27)
				)
				(justify mirror)
			)
		)
		(property "Value" ""
			(at 0 0 0)
			(layer "B.Fab")
			(effects
				(font
					(size 1.27 1.27)
				)
				(justify mirror)
			)
		)
		(duplicate_pad_numbers_are_jumpers no)
		(fp_line
			(start 0.7874 0.4064)
			(end 0.7874 -0.4064)
			(stroke
				(width 0.1524)
				(type default)
			)
			(layer "B.SilkS")
		)
		(fp_line
			(start 0.7874 -0.4064)
			(end -0.7874 -0.4064)
			(stroke
				(width 0.1524)
				(type default)
			)
			(layer "B.SilkS")
		)
		(fp_line
			(start -0.7874 0.4064)
			(end 0.7874 0.4064)
			(stroke
				(width 0.1524)
				(type default)
			)
			(layer "B.SilkS")
		)
		(fp_line
			(start -0.7874 -0.4064)
			(end -0.7874 0.4064)
			(stroke
				(width 0.1524)
				(type default)
			)
			(layer "B.SilkS")
		)
		(fp_line
			(start 0.67945 0.3048)
			(end 0.67945 -0.305054)
			(stroke
				(width 0.1)
				(type default)
			)
			(layer "B.Fab")
		)
		(fp_line
			(start 0.67945 -0.305054)
			(end 0.12065 -0.305054)
			(stroke
				(width 0.1)
				(type default)
			)
			(layer "B.Fab")
		)
		(fp_line
			(start 0.12065 0.3048)
			(end 0.67945 0.3048)
			(stroke
				(width 0.1)
				(type default)
			)
			(layer "B.Fab")
		)
		(fp_line
			(start 0.12065 0.2794)
			(end 0.12065 0.3048)
			(stroke
				(width 0.1)
				(type default)
			)
			(layer "B.Fab")
		)
		(fp_line
			(start 0.12065 -0.2794)
			(end -0.12065 -0.2794)
			(stroke
				(width 0.1)
				(type default)
			)
			(layer "B.Fab")
		)
		(fp_line
			(start 0.12065 -0.305054)
			(end 0.12065 -0.2794)
			(stroke
				(width 0.1)
				(type default)
			)
			(layer "B.Fab")
		)
		(fp_line
			(start -0.120396 0.3048)
			(end -0.120396 0.2794)
			(stroke
				(width 0.1)
				(type default)
			)
			(layer "B.Fab")
		)
		(fp_line
			(start -0.120396 0.2794)
			(end 0.12065 0.2794)
			(stroke
				(width 0.1)
				(type default)
			)
			(layer "B.Fab")
		)
		(fp_line
			(start -0.12065 -0.2794)
			(end -0.12065 -0.3048)
			(stroke
				(width 0.1)
				(type default)
			)
			(layer "B.Fab")
		)
		(fp_line
			(start -0.12065 -0.3048)
			(end -0.67945 -0.3048)
			(stroke
				(width 0.1)
				(type default)
			)
			(layer "B.Fab")
		)
		(fp_line
			(start -0.67945 0.3048)
			(end -0.120396 0.3048)
			(stroke
				(width 0.1)
				(type default)
			)
			(layer "B.Fab")
		)
		(fp_line
			(start -0.67945 -0.3048)
			(end -0.67945 0.3048)
			(stroke
				(width 0.1)
				(type default)
			)
			(layer "B.Fab")
		)
		(pad "1" smd circle
			(at 0.40005 0)
			(size 0 0)
			(layers "B.Cu" "B.Mask" "B.Paste")
			(net "SVID_PVDDCR_CPU0_P1_SVTI")
		)
		(pad "2" smd circle
			(at -0.40005 0)
			(size 0 0)
			(layers "B.Cu" "B.Mask" "B.Paste")
			(net "SVID_PVDDCR_CPU0_P1_SVTI_R")
		)
	)
)
